FILE_TYPE = CONNECTIVITY;
{Allegro Design Entry HDL 17.4-2019 S026 (4007227) 1/17/2022}
"PAGE_NUMBER" = 38;
0"NC";
1"M_B_CPU1_SA_DQ<31:0>";
2"M_B_CPU1_SB_DQ<31:0>";
3"M_B_CPU1_SA_CB<7:0>";
4"M_B_CPU1_SB_CB<7:0>";
5"M_B_CPU1_SA_DQS_DN<9:0>";
6"M_B_CPU1_SA_DQS_DP<9:0>";
7"M_B_CPU1_SB_DQS_DP<9:0>";
8"M_B_CPU1_SB_DQS_DN<9:0>";
9"M_B_CPU1_SA_CA<6:0>";
10"M_B_CPU1_SB_CA<6:0>";
11"M_B_CPU1_ALERT_N";
12"M_B_CPU1_ALERT_R_N";
13"TP_M_B_CPU1_SA_TEST39B";
14"M_B_CPU1_CLK_DP<0>";
15"M_B_CPU1_CLK_DN<0>";
16"M_B_CPU1_SA_CS_N<0>";
17"M_B_CPU1_SA_CS_N<1>";
18"M_B_CPU1_SA_RSP<0>";
19"M_B_CPU1_SA_PAR";
20"M_B_CPU1_SB_CS_N<1>";
21"M_B_CPU1_SB_CS_N<0>";
22"M_B_CPU1_SB_RSP<0>";
23"M_B_CPU1_SB_PAR";
24"M_B_CPU1_RESET_N";
25"M_B_CPU1_SB_DQS_DP<9>";
26"M_B_CPU1_SB_CA<6>";
27"M_B_CPU1_SA_CA<6>";
28"M_B_CPU1_SB_CA<5>";
29"M_B_CPU1_SA_CA<5>";
30"M_B_CPU1_SB_CA<4>";
31"M_B_CPU1_SA_CA<4>";
32"M_B_CPU1_SB_CA<3>";
33"M_B_CPU1_SA_CA<3>";
34"M_B_CPU1_SB_CA<2>";
35"M_B_CPU1_SA_CA<2>";
36"M_B_CPU1_SB_CA<1>";
37"M_B_CPU1_SA_CA<1>";
38"M_B_CPU1_SB_CA<0>";
39"M_B_CPU1_SA_CA<0>";
40"M_B_CPU1_SB_DQS_DN<9>";
41"M_B_CPU1_SB_DQS_DP<4>";
42"M_B_CPU1_SB_DQS_DN<8>";
43"M_B_CPU1_SB_DQS_DP<3>";
44"M_B_CPU1_SB_DQS_DN<7>";
45"M_B_CPU1_SB_DQS_DP<2>";
46"M_B_CPU1_SB_DQS_DN<6>";
47"M_B_CPU1_SB_DQS_DP<1>";
48"M_B_CPU1_SB_DQS_DN<5>";
49"M_B_CPU1_SB_DQS_DP<0>";
50"M_B_CPU1_SB_DQS_DN<4>";
51"M_B_CPU1_SA_DQS_DN<9>";
52"M_B_CPU1_SB_DQS_DN<3>";
53"M_B_CPU1_SB_DQS_DN<2>";
54"M_B_CPU1_SB_DQS_DN<1>";
55"M_B_CPU1_SB_DQS_DN<0>";
56"M_B_CPU1_SB_DQS_DP<8>";
57"M_B_CPU1_SB_DQS_DP<7>";
58"M_B_CPU1_SB_DQS_DP<6>";
59"M_B_CPU1_SB_DQS_DP<5>";
60"M_B_CPU1_SA_DQS_DP<9>";
61"M_B_CPU1_SA_DQS_DP<8>";
62"M_B_CPU1_SA_DQS_DP<7>";
63"M_B_CPU1_SA_DQS_DP<6>";
64"M_B_CPU1_SA_DQS_DP<5>";
65"M_B_CPU1_SA_DQS_DP<4>";
66"M_B_CPU1_SA_DQS_DN<8>";
67"M_B_CPU1_SA_DQS_DP<3>";
68"M_B_CPU1_SA_DQS_DN<7>";
69"M_B_CPU1_SA_DQS_DP<2>";
70"M_B_CPU1_SA_DQS_DN<6>";
71"M_B_CPU1_SA_DQS_DP<1>";
72"M_B_CPU1_SA_DQS_DN<5>";
73"M_B_CPU1_SA_DQS_DP<0>";
74"M_B_CPU1_SA_DQS_DN<4>";
75"M_B_CPU1_SA_DQS_DN<3>";
76"M_B_CPU1_SA_DQS_DN<2>";
77"M_B_CPU1_SA_DQS_DN<1>";
78"M_B_CPU1_SA_DQS_DN<0>";
79"M_B_CPU1_SB_CB<7>";
80"M_B_CPU1_SB_CB<6>";
81"M_B_CPU1_SB_CB<5>";
82"M_B_CPU1_SB_CB<4>";
83"M_B_CPU1_SB_CB<3>";
84"M_B_CPU1_SB_CB<2>";
85"M_B_CPU1_SB_CB<1>";
86"M_B_CPU1_SB_CB<0>";
87"M_B_CPU1_SA_CB<1>";
88"M_B_CPU1_SA_CB<0>";
89"M_B_CPU1_SB_DQ<29>";
90"M_B_CPU1_SB_DQ<28>";
91"M_B_CPU1_SB_DQ<27>";
92"M_B_CPU1_SB_DQ<26>";
93"M_B_CPU1_SB_DQ<25>";
94"M_B_CPU1_SB_DQ<24>";
95"M_B_CPU1_SB_DQ<23>";
96"M_B_CPU1_SB_DQ<22>";
97"M_B_CPU1_SA_CB<7>";
98"M_B_CPU1_SA_CB<6>";
99"M_B_CPU1_SB_DQ<31>";
100"M_B_CPU1_SA_CB<5>";
101"M_B_CPU1_SB_DQ<30>";
102"M_B_CPU1_SA_CB<4>";
103"M_B_CPU1_SA_CB<3>";
104"M_B_CPU1_SA_CB<2>";
105"M_B_CPU1_SB_DQ<20>";
106"M_B_CPU1_SB_DQ<19>";
107"M_B_CPU1_SB_DQ<18>";
108"M_B_CPU1_SB_DQ<9>";
109"M_B_CPU1_SB_DQ<17>";
110"M_B_CPU1_SB_DQ<8>";
111"M_B_CPU1_SB_DQ<16>";
112"M_B_CPU1_SB_DQ<7>";
113"M_B_CPU1_SB_DQ<15>";
114"M_B_CPU1_SB_DQ<6>";
115"M_B_CPU1_SB_DQ<14>";
116"M_B_CPU1_SB_DQ<5>";
117"M_B_CPU1_SB_DQ<13>";
118"M_B_CPU1_SB_DQ<4>";
119"M_B_CPU1_SB_DQ<12>";
120"M_B_CPU1_SB_DQ<3>";
121"M_B_CPU1_SB_DQ<11>";
122"M_B_CPU1_SB_DQ<10>";
123"M_B_CPU1_SB_DQ<21>";
124"M_B_CPU1_SA_DQ<24>";
125"M_B_CPU1_SA_DQ<21>";
126"M_B_CPU1_SA_DQ<20>";
127"M_B_CPU1_SA_DQ<31>";
128"M_B_CPU1_SA_DQ<30>";
129"M_B_CPU1_SA_DQ<19>";
130"M_B_CPU1_SA_DQ<18>";
131"M_B_CPU1_SA_DQ<29>";
132"M_B_CPU1_SA_DQ<17>";
133"M_B_CPU1_SA_DQ<28>";
134"M_B_CPU1_SA_DQ<27>";
135"M_B_CPU1_SB_DQ<2>";
136"M_B_CPU1_SA_DQ<26>";
137"M_B_CPU1_SB_DQ<1>";
138"M_B_CPU1_SA_DQ<25>";
139"M_B_CPU1_SB_DQ<0>";
140"M_B_CPU1_SA_DQ<23>";
141"M_B_CPU1_SA_DQ<22>";
142"M_B_CPU1_SA_DQ<10>";
143"M_B_CPU1_SA_DQ<9>";
144"M_B_CPU1_SA_DQ<8>";
145"M_B_CPU1_SA_DQ<7>";
146"M_B_CPU1_SA_DQ<6>";
147"M_B_CPU1_SA_DQ<5>";
148"M_B_CPU1_SA_DQ<4>";
149"M_B_CPU1_SA_DQ<3>";
150"M_B_CPU1_SA_DQ<16>";
151"M_B_CPU1_SA_DQ<2>";
152"M_B_CPU1_SA_DQ<15>";
153"M_B_CPU1_SA_DQ<1>";
154"M_B_CPU1_SA_DQ<14>";
155"M_B_CPU1_SA_DQ<0>";
156"M_B_CPU1_SA_DQ<13>";
157"M_B_CPU1_SA_DQ<12>";
158"M_B_CPU1_SA_DQ<11>";
%"GENOA_SP5"
"2","(-4725,3625)","0","pure_quanta","I159";
;
LOCATION"U26"
$SEC"2"
CDS_SEC"2"
PART_TYPE"SMLF"
MATERIAL"IO"
VALUE"SOCKET6096_13568-001"
CDS_LIB"pure_quanta"
NEEDS_NO_SIZE"TRUE"
CDS_LMAN_SYM_OUTLINE"-650,2550,650,-2550"
PART_NUMBER"DGA^6000030";
"TEST39B"
$PN"BF62"13;
"MBB_DATA20"
$PN"CV63"105;
"MBA_DATA24"
$PN"AC64"124;
"MBB_DATA19"
$PN"CT62"106;
"MB1_CLK_L"
$PN"BG64"0;
"MB1_CLK_H"
$PN"BF63"0;
"MB0_CLK_L"
$PN"BD63"15;
"MB0_CLK_H"
$PN"BC64"14;
"MBB_PAR"
$PN"BL64"23;
"MBA_PAR"
$PN"BC62"19;
"MBB_DQS_H9"
$PN"BV63"25;
"MBA_CHECK1"
$PN"AK62"87;
"MBA_DATA10"
$PN"M63"142;
"MBA_DATA21"
$PN"AB62"125;
"MBB_DQS_H4"
$PN"BY62"41;
"MBB_DQS_L8"
$PN"DC62"42;
"MBA1_CS_L1"
$PN"AV62"0;
"MBA_CHECK0"
$PN"AJ64"88;
"MBA_DATA20"
$PN"AA64"126;
"MBA_DATA31"
$PN"AJ62"127;
"MBA_DQS_H9"
$PN"AN62"60;
"MBB_CA6"
$PN"BK63"26;
"MBB_DQS_H3"
$PN"DB63"43;
"MBB_DQS_L7"
$PN"CU62"44;
"MBA0_CS_L1"
$PN"AW62"17;
"MBA1_CS_L0"
$PN"AU64"0;
"MBA_CA6"
$PN"BB62"27;
"MBA_DATA30"
$PN"AH63"128;
"MBA_DQS_H8"
$PN"AG62"61;
"MBB_CA5"
$PN"BK62"28;
"MBB_DQS_H2"
$PN"CT63"45;
"MBB_DQS_L6"
$PN"CL62"46;
"MBA0_CS_L0"
$PN"AV63"16;
"MBA_CA5"
$PN"BB63"29;
"MBA_DQS_H7"
$PN"AA62"62;
"MBB_CA4"
$PN"BJ62"30;
"MBB_DATA18"
$PN"CR64"107;
"MBB_DATA29"
$PN"DE62"89;
"MBB_DQS_H1"
$PN"CK63"47;
"MBB_DQS_L5"
$PN"CE62"48;
"MBA_CA4"
$PN"BA64"31;
"MBA_DQS_H6"
$PN"R62"63;
"MBB1_RSP_L"
$PN"BR64"0;
"MBB_CA3"
$PN"BJ64"32;
"MBB_DATA9"
$PN"CJ62"108;
"MBB_DATA17"
$PN"CR62"109;
"MBB_DATA28"
$PN"DD63"90;
"MBB_DQS_H0"
$PN"CD63"49;
"MBB_DQS_L4"
$PN"BW62"50;
"MBA_CA3"
$PN"BA62"33;
"MBA_DATA9"
$PN"M62"143;
"MBA_DQS_H5"
$PN"J62"64;
"MBA_DQS_L9"
$PN"AM62"51;
"MBB0_RSP_L"
$PN"BP63"22;
"MBB_CA2"
$PN"BH63"34;
"MBB_CHECK7"
$PN"BV62"79;
"MBB_DATA8"
$PN"CH63"110;
"MBB_DATA16"
$PN"CP63"111;
"MBB_DATA27"
$PN"DB62"91;
"MBB_DQS_L3"
$PN"DC64"52;
"MBA_CA2"
$PN"AY62"35;
"MBA_DATA8"
$PN"L64"144;
"MBA_DQS_H4"
$PN"AL64"65;
"MBA_DQS_L8"
$PN"AF62"66;
"MBB_CA1"
$PN"BH62"36;
"MBB_CHECK6"
$PN"BU64"80;
"MBB_DATA7"
$PN"CH62"112;
"MBB_DATA15"
$PN"CP62"113;
"MBB_DATA26"
$PN"DA64"92;
"MBB_DQS_L2"
$PN"CU64"53;
"MBA_CA1"
$PN"AY63"37;
"MBA_DATA7"
$PN"L62"145;
"MBA_DQS_H3"
$PN"AE64"67;
"MBA_DQS_L7"
$PN"Y62"68;
"MBB_CA0"
$PN"BG62"38;
"MBB_CHECK5"
$PN"BU62"81;
"MBB_DATA6"
$PN"CG64"114;
"MBB_DATA14"
$PN"CN64"115;
"MBB_DATA25"
$PN"DA62"93;
"MBB_DQS_L1"
$PN"CL64"54;
"MBA_CA0"
$PN"AW64"39;
"MBA_DATA6"
$PN"K63"146;
"MBA_DATA19"
$PN"W62"129;
"MBA_DQS_H2"
$PN"W64"69;
"MBA_DQS_L6"
$PN"P62"70;
"MBB_CHECK4"
$PN"BT63"82;
"MBB_DATA5"
$PN"CG62"116;
"MBB_DATA13"
$PN"CN62"117;
"MBB_DATA24"
$PN"CY63"94;
"MBB_DQS_L0"
$PN"CE64"55;
"MBA_DATA5"
$PN"K62"147;
"MBA_DATA18"
$PN"V63"130;
"MBA_DATA29"
$PN"AH62"131;
"MBA_DQS_H1"
$PN"N64"71;
"MBA_DQS_L5"
$PN"H62"72;
"MBB_CHECK3"
$PN"CB62"83;
"MBB_DATA4"
$PN"CF63"118;
"MBB_DATA12"
$PN"CM63"119;
"MBB_DATA23"
$PN"CY62"95;
"MBA1_RSP_L"
$PN"BP62"0;
"MBA_DATA4"
$PN"J64"148;
"MBA_DATA17"
$PN"V62"132;
"MBA_DATA28"
$PN"AG64"133;
"MBA_DQS_H0"
$PN"G64"73;
"MBA_DQS_L4"
$PN"AM63"74;
"MBB_CHECK2"
$PN"CA64"84;
"MBB_DATA3"
$PN"CD62"120;
"MBB_DATA11"
$PN"CK62"121;
"MBB_DATA22"
$PN"CW64"96;
"MBA0_RSP_L"
$PN"BN62"18;
"MBA_CHECK7"
$PN"AR62"97;
"MBA_DATA3"
$PN"G62"149;
"MBA_DATA16"
$PN"U64"150;
"MBA_DATA27"
$PN"AE62"134;
"MBA_DQS_L3"
$PN"AF63"75;
"MBB_CHECK1"
$PN"CA62"85;
"MBB_DATA2"
$PN"CC64"135;
"MBB_DATA10"
$PN"CJ64"122;
"MBB_DATA21"
$PN"CW62"123;
"MBA_CHECK6"
$PN"AP63"98;
"MBA_DATA2"
$PN"F63"151;
"MBA_DATA15"
$PN"U62"152;
"MBA_DATA26"
$PN"AD63"136;
"MBA_DQS_L2"
$PN"Y63"76;
"MBB1_CS_L1"
$PN"BM63"0;
"MBB_CHECK0"
$PN"BY63"86;
"MBB_DATA1"
$PN"CC62"137;
"MBB_DATA31"
$PN"DF62"99;
"MBA_CHECK5"
$PN"AP62"100;
"MBA_DATA1"
$PN"F62"153;
"MBA_DATA14"
$PN"T63"154;
"MBA_DATA25"
$PN"AD62"138;
"MBA_DQS_L1"
$PN"P63"77;
"MBB0_CS_L1"
$PN"BN64"20;
"MBB1_CS_L0"
$PN"BL62"0;
"MBB_DATA0"
$PN"CB63"139;
"MBB_DATA30"
$PN"DE64"101;
"MBB_DQS_H8"
$PN"DD62"56;
"MBA_CHECK4"
$PN"AN64"102;
"MBA_DATA0"
$PN"E64"155;
"MBA_DATA13"
$PN"T62"156;
"MBA_DQS_L0"
$PN"H63"78;
"MBB0_CS_L0"
$PN"BM62"21;
"MBB_DQS_H7"
$PN"CV62"57;
"MBA_CHECK3"
$PN"AL62"103;
"MBA_DATA12"
$PN"R64"157;
"MBA_DATA23"
$PN"AC62"140;
"MBB_DQS_H6"
$PN"CM62"58;
"MBA_CHECK2"
$PN"AK63"104;
"MBA_DATA11"
$PN"N62"158;
"MBA_DATA22"
$PN"AB63"141;
"MBB_DQS_H5"
$PN"CF62"59;
"MBB_DQS_L9"
$PN"BW64"40;
"MB_RESET_L"
$PN"AU62"24;
"MB_ALERT_L"
$PN"AT62"12;
%"TAP"
"1","(-3450,5925)","0","mstr_standard","I162";
;
CDS_LIB"mstr_standard"
BODY_TYPE"PLUMBING"
HDL_TAP"TRUE";
"B \NAC \NWC"1;
"S \NAC"
BN"2"151;
%"TAP"
"1","(-3450,5975)","0","mstr_standard","I163";
;
CDS_LIB"mstr_standard"
BODY_TYPE"PLUMBING"
HDL_TAP"TRUE";
"B \NAC \NWC"1;
"S \NAC"
BN"1"153;
%"TAP"
"1","(-3450,6025)","0","mstr_standard","I164";
;
CDS_LIB"mstr_standard"
BODY_TYPE"PLUMBING"
HDL_TAP"TRUE";
"B \NAC \NWC"1;
"S \NAC"
BN"0"155;
%"TAP"
"1","(-3450,5825)","0","mstr_standard","I165";
;
CDS_LIB"mstr_standard"
BODY_TYPE"PLUMBING"
HDL_TAP"TRUE";
"B \NAC \NWC"1;
"S \NAC"
BN"4"148;
%"TAP"
"1","(-3450,5875)","0","mstr_standard","I166";
;
CDS_LIB"mstr_standard"
BODY_TYPE"PLUMBING"
HDL_TAP"TRUE";
"B \NAC \NWC"1;
"S \NAC"
BN"3"149;
%"TAP"
"1","(-3450,5775)","0","mstr_standard","I167";
;
CDS_LIB"mstr_standard"
BODY_TYPE"PLUMBING"
HDL_TAP"TRUE";
"B \NAC \NWC"1;
"S \NAC"
BN"5"147;
%"TAP"
"1","(-3450,5725)","0","mstr_standard","I168";
;
CDS_LIB"mstr_standard"
BODY_TYPE"PLUMBING"
HDL_TAP"TRUE";
"B \NAC \NWC"1;
"S \NAC"
BN"6"146;
%"TAP"
"1","(-3450,5675)","0","mstr_standard","I169";
;
CDS_LIB"mstr_standard"
BODY_TYPE"PLUMBING"
HDL_TAP"TRUE";
"B \NAC \NWC"1;
"S \NAC"
BN"7"145;
%"TAP"
"1","(-3450,5575)","0","mstr_standard","I170";
;
CDS_LIB"mstr_standard"
BODY_TYPE"PLUMBING"
HDL_TAP"TRUE";
"B \NAC \NWC"1;
"S \NAC"
BN"8"144;
%"TAP"
"1","(-3450,5425)","0","mstr_standard","I171";
;
CDS_LIB"mstr_standard"
BODY_TYPE"PLUMBING"
HDL_TAP"TRUE";
"B \NAC \NWC"1;
"S \NAC"
BN"11"158;
%"TAP"
"1","(-3450,5475)","0","mstr_standard","I172";
;
CDS_LIB"mstr_standard"
BODY_TYPE"PLUMBING"
HDL_TAP"TRUE";
"B \NAC \NWC"1;
"S \NAC"
BN"10"142;
%"TAP"
"1","(-3450,5525)","0","mstr_standard","I173";
;
CDS_LIB"mstr_standard"
BODY_TYPE"PLUMBING"
HDL_TAP"TRUE";
"B \NAC \NWC"1;
"S \NAC"
BN"9"143;
%"TAP"
"1","(-3450,5375)","0","mstr_standard","I174";
;
CDS_LIB"mstr_standard"
BODY_TYPE"PLUMBING"
HDL_TAP"TRUE";
"B \NAC \NWC"1;
"S \NAC"
BN"12"157;
%"TAP"
"1","(-3450,5325)","0","mstr_standard","I175";
;
CDS_LIB"mstr_standard"
BODY_TYPE"PLUMBING"
HDL_TAP"TRUE";
"B \NAC \NWC"1;
"S \NAC"
BN"13"156;
%"TAP"
"1","(-3450,5275)","0","mstr_standard","I176";
;
CDS_LIB"mstr_standard"
BODY_TYPE"PLUMBING"
HDL_TAP"TRUE";
"B \NAC \NWC"1;
"S \NAC"
BN"14"154;
%"TAP"
"1","(-3450,5225)","0","mstr_standard","I177";
;
CDS_LIB"mstr_standard"
BODY_TYPE"PLUMBING"
HDL_TAP"TRUE";
"B \NAC \NWC"1;
"S \NAC"
BN"15"152;
%"TAP"
"1","(-3450,5125)","0","mstr_standard","I178";
;
CDS_LIB"mstr_standard"
BODY_TYPE"PLUMBING"
HDL_TAP"TRUE";
"B \NAC \NWC"1;
"S \NAC"
BN"16"150;
%"TAP"
"1","(-3450,5075)","0","mstr_standard","I179";
;
CDS_LIB"mstr_standard"
BODY_TYPE"PLUMBING"
HDL_TAP"TRUE";
"B \NAC \NWC"1;
"S \NAC"
BN"17"132;
%"TAP"
"1","(-3450,5025)","0","mstr_standard","I180";
;
CDS_LIB"mstr_standard"
BODY_TYPE"PLUMBING"
HDL_TAP"TRUE";
"B \NAC \NWC"1;
"S \NAC"
BN"18"130;
%"TAP"
"1","(-3450,4925)","0","mstr_standard","I181";
;
CDS_LIB"mstr_standard"
BODY_TYPE"PLUMBING"
HDL_TAP"TRUE";
"B \NAC \NWC"1;
"S \NAC"
BN"20"126;
%"TAP"
"1","(-3450,4975)","0","mstr_standard","I182";
;
CDS_LIB"mstr_standard"
BODY_TYPE"PLUMBING"
HDL_TAP"TRUE";
"B \NAC \NWC"1;
"S \NAC"
BN"19"129;
%"TAP"
"1","(-3450,4875)","0","mstr_standard","I183";
;
CDS_LIB"mstr_standard"
BODY_TYPE"PLUMBING"
HDL_TAP"TRUE";
"B \NAC \NWC"1;
"S \NAC"
BN"21"125;
%"TAP"
"1","(-3450,4825)","0","mstr_standard","I184";
;
CDS_LIB"mstr_standard"
BODY_TYPE"PLUMBING"
HDL_TAP"TRUE";
"B \NAC \NWC"1;
"S \NAC"
BN"22"141;
%"TAP"
"1","(-3450,4775)","0","mstr_standard","I185";
;
CDS_LIB"mstr_standard"
BODY_TYPE"PLUMBING"
HDL_TAP"TRUE";
"B \NAC \NWC"1;
"S \NAC"
BN"23"140;
%"TAP"
"1","(-3450,4675)","0","mstr_standard","I186";
;
CDS_LIB"mstr_standard"
BODY_TYPE"PLUMBING"
HDL_TAP"TRUE";
"B \NAC \NWC"1;
"S \NAC"
BN"24"124;
%"TAP"
"1","(-3450,4625)","0","mstr_standard","I187";
;
CDS_LIB"mstr_standard"
BODY_TYPE"PLUMBING"
HDL_TAP"TRUE";
"B \NAC \NWC"1;
"S \NAC"
BN"25"138;
%"TAP"
"1","(-3450,4575)","0","mstr_standard","I188";
;
CDS_LIB"mstr_standard"
BODY_TYPE"PLUMBING"
HDL_TAP"TRUE";
"B \NAC \NWC"1;
"S \NAC"
BN"26"136;
%"TAP"
"1","(-3450,4525)","0","mstr_standard","I189";
;
CDS_LIB"mstr_standard"
BODY_TYPE"PLUMBING"
HDL_TAP"TRUE";
"B \NAC \NWC"1;
"S \NAC"
BN"27"134;
%"TAP"
"1","(-3450,4425)","0","mstr_standard","I190";
;
CDS_LIB"mstr_standard"
BODY_TYPE"PLUMBING"
HDL_TAP"TRUE";
"B \NAC \NWC"1;
"S \NAC"
BN"29"131;
%"TAP"
"1","(-3450,4375)","0","mstr_standard","I191";
;
CDS_LIB"mstr_standard"
BODY_TYPE"PLUMBING"
HDL_TAP"TRUE";
"B \NAC \NWC"1;
"S \NAC"
BN"30"128;
%"TAP"
"1","(-3450,4475)","0","mstr_standard","I192";
;
CDS_LIB"mstr_standard"
BODY_TYPE"PLUMBING"
HDL_TAP"TRUE";
"B \NAC \NWC"1;
"S \NAC"
BN"28"133;
%"TAP"
"1","(-3450,4325)","0","mstr_standard","I193";
;
CDS_LIB"mstr_standard"
BODY_TYPE"PLUMBING"
HDL_TAP"TRUE";
"B \NAC \NWC"1;
"S \NAC"
BN"31"127;
%"TAP"
"1","(-3450,4125)","0","mstr_standard","I194";
;
CDS_LIB"mstr_standard"
BODY_TYPE"PLUMBING"
HDL_TAP"TRUE";
"B \NAC \NWC"2;
"S \NAC"
BN"2"135;
%"TAP"
"1","(-3450,4175)","0","mstr_standard","I195";
;
CDS_LIB"mstr_standard"
BODY_TYPE"PLUMBING"
HDL_TAP"TRUE";
"B \NAC \NWC"2;
"S \NAC"
BN"1"137;
%"TAP"
"1","(-3450,4225)","0","mstr_standard","I196";
;
CDS_LIB"mstr_standard"
BODY_TYPE"PLUMBING"
HDL_TAP"TRUE";
"B \NAC \NWC"2;
"S \NAC"
BN"0"139;
%"TAP"
"1","(-3450,4075)","0","mstr_standard","I198";
;
CDS_LIB"mstr_standard"
BODY_TYPE"PLUMBING"
HDL_TAP"TRUE";
"B \NAC \NWC"2;
"S \NAC"
BN"3"120;
%"TAP"
"1","(-3450,4025)","0","mstr_standard","I199";
;
CDS_LIB"mstr_standard"
BODY_TYPE"PLUMBING"
HDL_TAP"TRUE";
"B \NAC \NWC"2;
"S \NAC"
BN"4"118;
%"TAP"
"1","(-3450,3975)","0","mstr_standard","I200";
;
CDS_LIB"mstr_standard"
BODY_TYPE"PLUMBING"
HDL_TAP"TRUE";
"B \NAC \NWC"2;
"S \NAC"
BN"5"116;
%"TAP"
"1","(-3450,3875)","0","mstr_standard","I201";
;
CDS_LIB"mstr_standard"
BODY_TYPE"PLUMBING"
HDL_TAP"TRUE";
"B \NAC \NWC"2;
"S \NAC"
BN"7"112;
%"TAP"
"1","(-3450,3925)","0","mstr_standard","I202";
;
CDS_LIB"mstr_standard"
BODY_TYPE"PLUMBING"
HDL_TAP"TRUE";
"B \NAC \NWC"2;
"S \NAC"
BN"6"114;
%"TAP"
"1","(-3450,3775)","0","mstr_standard","I203";
;
CDS_LIB"mstr_standard"
BODY_TYPE"PLUMBING"
HDL_TAP"TRUE";
"B \NAC \NWC"2;
"S \NAC"
BN"8"110;
%"TAP"
"1","(-3450,3625)","0","mstr_standard","I204";
;
CDS_LIB"mstr_standard"
BODY_TYPE"PLUMBING"
HDL_TAP"TRUE";
"B \NAC \NWC"2;
"S \NAC"
BN"11"121;
%"TAP"
"1","(-3450,3725)","0","mstr_standard","I205";
;
CDS_LIB"mstr_standard"
BODY_TYPE"PLUMBING"
HDL_TAP"TRUE";
"B \NAC \NWC"2;
"S \NAC"
BN"9"108;
%"TAP"
"1","(-3450,3675)","0","mstr_standard","I206";
;
CDS_LIB"mstr_standard"
BODY_TYPE"PLUMBING"
HDL_TAP"TRUE";
"B \NAC \NWC"2;
"S \NAC"
BN"10"122;
%"TAP"
"1","(-3450,3575)","0","mstr_standard","I207";
;
CDS_LIB"mstr_standard"
BODY_TYPE"PLUMBING"
HDL_TAP"TRUE";
"B \NAC \NWC"2;
"S \NAC"
BN"12"119;
%"TAP"
"1","(-3450,3525)","0","mstr_standard","I208";
;
CDS_LIB"mstr_standard"
BODY_TYPE"PLUMBING"
HDL_TAP"TRUE";
"B \NAC \NWC"2;
"S \NAC"
BN"13"117;
%"TAP"
"1","(-3450,3425)","0","mstr_standard","I209";
;
CDS_LIB"mstr_standard"
BODY_TYPE"PLUMBING"
HDL_TAP"TRUE";
"B \NAC \NWC"2;
"S \NAC"
BN"15"113;
%"TAP"
"1","(-3450,3475)","0","mstr_standard","I210";
;
CDS_LIB"mstr_standard"
BODY_TYPE"PLUMBING"
HDL_TAP"TRUE";
"B \NAC \NWC"2;
"S \NAC"
BN"14"115;
%"TAP"
"1","(-3450,3325)","0","mstr_standard","I211";
;
CDS_LIB"mstr_standard"
BODY_TYPE"PLUMBING"
HDL_TAP"TRUE";
"B \NAC \NWC"2;
"S \NAC"
BN"16"111;
%"TAP"
"1","(-3450,3275)","0","mstr_standard","I212";
;
CDS_LIB"mstr_standard"
BODY_TYPE"PLUMBING"
HDL_TAP"TRUE";
"B \NAC \NWC"2;
"S \NAC"
BN"17"109;
%"TAP"
"1","(-3450,3225)","0","mstr_standard","I213";
;
CDS_LIB"mstr_standard"
BODY_TYPE"PLUMBING"
HDL_TAP"TRUE";
"B \NAC \NWC"2;
"S \NAC"
BN"18"107;
%"TAP"
"1","(-3450,3075)","0","mstr_standard","I214";
;
CDS_LIB"mstr_standard"
BODY_TYPE"PLUMBING"
HDL_TAP"TRUE";
"B \NAC \NWC"2;
"S \NAC"
BN"21"123;
%"TAP"
"1","(-3450,3125)","0","mstr_standard","I215";
;
CDS_LIB"mstr_standard"
BODY_TYPE"PLUMBING"
HDL_TAP"TRUE";
"B \NAC \NWC"2;
"S \NAC"
BN"20"105;
%"TAP"
"1","(-3450,3175)","0","mstr_standard","I216";
;
CDS_LIB"mstr_standard"
BODY_TYPE"PLUMBING"
HDL_TAP"TRUE";
"B \NAC \NWC"2;
"S \NAC"
BN"19"106;
%"TAP"
"1","(-3450,2825)","0","mstr_standard","I217";
;
CDS_LIB"mstr_standard"
BODY_TYPE"PLUMBING"
HDL_TAP"TRUE";
"B \NAC \NWC"2;
"S \NAC"
BN"25"93;
%"TAP"
"1","(-3450,2875)","0","mstr_standard","I218";
;
CDS_LIB"mstr_standard"
BODY_TYPE"PLUMBING"
HDL_TAP"TRUE";
"B \NAC \NWC"2;
"S \NAC"
BN"24"94;
%"TAP"
"1","(-3450,3025)","0","mstr_standard","I219";
;
CDS_LIB"mstr_standard"
BODY_TYPE"PLUMBING"
HDL_TAP"TRUE";
"B \NAC \NWC"2;
"S \NAC"
BN"22"96;
%"TAP"
"1","(-3450,2975)","0","mstr_standard","I220";
;
CDS_LIB"mstr_standard"
BODY_TYPE"PLUMBING"
HDL_TAP"TRUE";
"B \NAC \NWC"2;
"S \NAC"
BN"23"95;
%"TAP"
"1","(-3450,2575)","0","mstr_standard","I221";
;
CDS_LIB"mstr_standard"
BODY_TYPE"PLUMBING"
HDL_TAP"TRUE";
"B \NAC \NWC"2;
"S \NAC"
BN"30"101;
%"TAP"
"1","(-3450,2625)","0","mstr_standard","I222";
;
CDS_LIB"mstr_standard"
BODY_TYPE"PLUMBING"
HDL_TAP"TRUE";
"B \NAC \NWC"2;
"S \NAC"
BN"29"89;
%"TAP"
"1","(-3450,2675)","0","mstr_standard","I223";
;
CDS_LIB"mstr_standard"
BODY_TYPE"PLUMBING"
HDL_TAP"TRUE";
"B \NAC \NWC"2;
"S \NAC"
BN"28"90;
%"TAP"
"1","(-3450,2725)","0","mstr_standard","I224";
;
CDS_LIB"mstr_standard"
BODY_TYPE"PLUMBING"
HDL_TAP"TRUE";
"B \NAC \NWC"2;
"S \NAC"
BN"27"91;
%"TAP"
"1","(-3450,2775)","0","mstr_standard","I225";
;
CDS_LIB"mstr_standard"
BODY_TYPE"PLUMBING"
HDL_TAP"TRUE";
"B \NAC \NWC"2;
"S \NAC"
BN"26"92;
%"TAP"
"1","(-3450,2325)","0","mstr_standard","I226";
;
CDS_LIB"mstr_standard"
BODY_TYPE"PLUMBING"
HDL_TAP"TRUE";
"B \NAC \NWC"3;
"S \NAC"
BN"2"104;
%"TAP"
"1","(-3450,2375)","0","mstr_standard","I227";
;
CDS_LIB"mstr_standard"
BODY_TYPE"PLUMBING"
HDL_TAP"TRUE";
"B \NAC \NWC"3;
"S \NAC"
BN"1"87;
%"TAP"
"1","(-3450,2425)","0","mstr_standard","I228";
;
CDS_LIB"mstr_standard"
BODY_TYPE"PLUMBING"
HDL_TAP"TRUE";
"B \NAC \NWC"3;
"S \NAC"
BN"0"88;
%"TAP"
"1","(-3450,2525)","0","mstr_standard","I229";
;
CDS_LIB"mstr_standard"
BODY_TYPE"PLUMBING"
HDL_TAP"TRUE";
"B \NAC \NWC"2;
"S \NAC"
BN"31"99;
%"TAP"
"1","(-3450,2275)","0","mstr_standard","I230";
;
CDS_LIB"mstr_standard"
BODY_TYPE"PLUMBING"
HDL_TAP"TRUE";
"B \NAC \NWC"3;
"S \NAC"
BN"3"103;
%"TAP"
"1","(-3450,2225)","0","mstr_standard","I231";
;
CDS_LIB"mstr_standard"
BODY_TYPE"PLUMBING"
HDL_TAP"TRUE";
"B \NAC \NWC"3;
"S \NAC"
BN"4"102;
%"TAP"
"1","(-3450,2175)","0","mstr_standard","I232";
;
CDS_LIB"mstr_standard"
BODY_TYPE"PLUMBING"
HDL_TAP"TRUE";
"B \NAC \NWC"3;
"S \NAC"
BN"5"100;
%"TAP"
"1","(-3450,2075)","0","mstr_standard","I233";
;
CDS_LIB"mstr_standard"
BODY_TYPE"PLUMBING"
HDL_TAP"TRUE";
"B \NAC \NWC"3;
"S \NAC"
BN"7"97;
%"TAP"
"1","(-3450,2125)","0","mstr_standard","I234";
;
CDS_LIB"mstr_standard"
BODY_TYPE"PLUMBING"
HDL_TAP"TRUE";
"B \NAC \NWC"3;
"S \NAC"
BN"6"98;
%"TAP"
"1","(-3450,1975)","0","mstr_standard","I236";
;
CDS_LIB"mstr_standard"
BODY_TYPE"PLUMBING"
HDL_TAP"TRUE";
"B \NAC \NWC"4;
"S \NAC"
BN"0"86;
%"TAP"
"1","(-3450,1925)","0","mstr_standard","I237";
;
CDS_LIB"mstr_standard"
BODY_TYPE"PLUMBING"
HDL_TAP"TRUE";
"B \NAC \NWC"4;
"S \NAC"
BN"1"85;
%"TAP"
"1","(-3450,1875)","0","mstr_standard","I238";
;
CDS_LIB"mstr_standard"
BODY_TYPE"PLUMBING"
HDL_TAP"TRUE";
"B \NAC \NWC"4;
"S \NAC"
BN"2"84;
%"TAP"
"1","(-3450,1825)","0","mstr_standard","I239";
;
CDS_LIB"mstr_standard"
BODY_TYPE"PLUMBING"
HDL_TAP"TRUE";
"B \NAC \NWC"4;
"S \NAC"
BN"3"83;
%"TAP"
"1","(-3450,1775)","0","mstr_standard","I240";
;
CDS_LIB"mstr_standard"
BODY_TYPE"PLUMBING"
HDL_TAP"TRUE";
"B \NAC \NWC"4;
"S \NAC"
BN"4"82;
%"TAP"
"1","(-3450,1725)","0","mstr_standard","I241";
;
CDS_LIB"mstr_standard"
BODY_TYPE"PLUMBING"
HDL_TAP"TRUE";
"B \NAC \NWC"4;
"S \NAC"
BN"5"81;
%"TAP"
"1","(-3450,1625)","0","mstr_standard","I242";
;
CDS_LIB"mstr_standard"
BODY_TYPE"PLUMBING"
HDL_TAP"TRUE";
"B \NAC \NWC"4;
"S \NAC"
BN"7"79;
%"TAP"
"1","(-3450,1675)","0","mstr_standard","I243";
;
CDS_LIB"mstr_standard"
BODY_TYPE"PLUMBING"
HDL_TAP"TRUE";
"B \NAC \NWC"4;
"S \NAC"
BN"6"80;
%"TAP"
"1","(-5875,6025)","2","mstr_standard","I244";
;
CDS_LIB"mstr_standard"
BODY_TYPE"PLUMBING"
HDL_TAP"TRUE";
"B \NAC \NWC"6;
"S \NAC"
BN"0"73;
%"TAP"
"1","(-5875,5925)","2","mstr_standard","I245";
;
CDS_LIB"mstr_standard"
BODY_TYPE"PLUMBING"
HDL_TAP"TRUE";
"B \NAC \NWC"6;
"S \NAC"
BN"1"71;
%"TAP"
"1","(-5875,5825)","2","mstr_standard","I246";
;
CDS_LIB"mstr_standard"
BODY_TYPE"PLUMBING"
HDL_TAP"TRUE";
"B \NAC \NWC"6;
"S \NAC"
BN"2"69;
%"TAP"
"1","(-5875,5725)","2","mstr_standard","I247";
;
CDS_LIB"mstr_standard"
BODY_TYPE"PLUMBING"
HDL_TAP"TRUE";
"B \NAC \NWC"6;
"S \NAC"
BN"3"67;
%"TAP"
"1","(-6075,5975)","2","mstr_standard","I248";
;
CDS_LIB"mstr_standard"
BODY_TYPE"PLUMBING"
HDL_TAP"TRUE";
"B \NAC \NWC"5;
"S \NAC"
BN"0"78;
%"TAP"
"1","(-6075,5875)","2","mstr_standard","I249";
;
CDS_LIB"mstr_standard"
BODY_TYPE"PLUMBING"
HDL_TAP"TRUE";
"B \NAC \NWC"5;
"S \NAC"
BN"1"77;
%"TAP"
"1","(-6075,5675)","2","mstr_standard","I250";
;
CDS_LIB"mstr_standard"
BODY_TYPE"PLUMBING"
HDL_TAP"TRUE";
"B \NAC \NWC"5;
"S \NAC"
BN"3"75;
%"TAP"
"1","(-6075,5775)","2","mstr_standard","I251";
;
CDS_LIB"mstr_standard"
BODY_TYPE"PLUMBING"
HDL_TAP"TRUE";
"B \NAC \NWC"5;
"S \NAC"
BN"2"76;
%"TAP"
"1","(-5875,5625)","2","mstr_standard","I252";
;
CDS_LIB"mstr_standard"
BODY_TYPE"PLUMBING"
HDL_TAP"TRUE";
"B \NAC \NWC"6;
"S \NAC"
BN"4"65;
%"TAP"
"1","(-5875,5525)","2","mstr_standard","I253";
;
CDS_LIB"mstr_standard"
BODY_TYPE"PLUMBING"
HDL_TAP"TRUE";
"B \NAC \NWC"6;
"S \NAC"
BN"5"64;
%"TAP"
"1","(-5875,5425)","2","mstr_standard","I254";
;
CDS_LIB"mstr_standard"
BODY_TYPE"PLUMBING"
HDL_TAP"TRUE";
"B \NAC \NWC"6;
"S \NAC"
BN"6"63;
%"TAP"
"1","(-5875,5325)","2","mstr_standard","I255";
;
CDS_LIB"mstr_standard"
BODY_TYPE"PLUMBING"
HDL_TAP"TRUE";
"B \NAC \NWC"6;
"S \NAC"
BN"7"62;
%"TAP"
"1","(-5875,5125)","2","mstr_standard","I256";
;
CDS_LIB"mstr_standard"
BODY_TYPE"PLUMBING"
HDL_TAP"TRUE";
"B \NAC \NWC"6;
"S \NAC"
BN"9"60;
%"TAP"
"1","(-5875,5225)","2","mstr_standard","I257";
;
CDS_LIB"mstr_standard"
BODY_TYPE"PLUMBING"
HDL_TAP"TRUE";
"B \NAC \NWC"6;
"S \NAC"
BN"8"61;
%"TAP"
"1","(-6075,5475)","2","mstr_standard","I258";
;
CDS_LIB"mstr_standard"
BODY_TYPE"PLUMBING"
HDL_TAP"TRUE";
"B \NAC \NWC"5;
"S \NAC"
BN"5"72;
%"TAP"
"1","(-6075,5575)","2","mstr_standard","I259";
;
CDS_LIB"mstr_standard"
BODY_TYPE"PLUMBING"
HDL_TAP"TRUE";
"B \NAC \NWC"5;
"S \NAC"
BN"4"74;
%"TAP"
"1","(-6075,5375)","2","mstr_standard","I260";
;
CDS_LIB"mstr_standard"
BODY_TYPE"PLUMBING"
HDL_TAP"TRUE";
"B \NAC \NWC"5;
"S \NAC"
BN"6"70;
%"TAP"
"1","(-6075,5275)","2","mstr_standard","I261";
;
CDS_LIB"mstr_standard"
BODY_TYPE"PLUMBING"
HDL_TAP"TRUE";
"B \NAC \NWC"5;
"S \NAC"
BN"7"68;
%"TAP"
"1","(-6075,5175)","2","mstr_standard","I262";
;
CDS_LIB"mstr_standard"
BODY_TYPE"PLUMBING"
HDL_TAP"TRUE";
"B \NAC \NWC"5;
"S \NAC"
BN"8"66;
%"TAP"
"1","(-5875,4975)","2","mstr_standard","I263";
;
CDS_LIB"mstr_standard"
BODY_TYPE"PLUMBING"
HDL_TAP"TRUE";
"B \NAC \NWC"7;
"S \NAC"
BN"0"49;
%"TAP"
"1","(-5875,4875)","2","mstr_standard","I264";
;
CDS_LIB"mstr_standard"
BODY_TYPE"PLUMBING"
HDL_TAP"TRUE";
"B \NAC \NWC"7;
"S \NAC"
BN"1"47;
%"TAP"
"1","(-5875,4775)","2","mstr_standard","I265";
;
CDS_LIB"mstr_standard"
BODY_TYPE"PLUMBING"
HDL_TAP"TRUE";
"B \NAC \NWC"7;
"S \NAC"
BN"2"45;
%"TAP"
"1","(-5875,4675)","2","mstr_standard","I266";
;
CDS_LIB"mstr_standard"
BODY_TYPE"PLUMBING"
HDL_TAP"TRUE";
"B \NAC \NWC"7;
"S \NAC"
BN"3"43;
%"TAP"
"1","(-6075,4925)","2","mstr_standard","I267";
;
CDS_LIB"mstr_standard"
BODY_TYPE"PLUMBING"
HDL_TAP"TRUE";
"B \NAC \NWC"8;
"S \NAC"
BN"0"55;
%"TAP"
"1","(-6075,5075)","2","mstr_standard","I268";
;
CDS_LIB"mstr_standard"
BODY_TYPE"PLUMBING"
HDL_TAP"TRUE";
"B \NAC \NWC"5;
"S \NAC"
BN"9"51;
%"TAP"
"1","(-6075,4825)","2","mstr_standard","I269";
;
CDS_LIB"mstr_standard"
BODY_TYPE"PLUMBING"
HDL_TAP"TRUE";
"B \NAC \NWC"8;
"S \NAC"
BN"1"54;
%"TAP"
"1","(-6075,4725)","2","mstr_standard","I270";
;
CDS_LIB"mstr_standard"
BODY_TYPE"PLUMBING"
HDL_TAP"TRUE";
"B \NAC \NWC"8;
"S \NAC"
BN"2"53;
%"TAP"
"1","(-6075,4625)","2","mstr_standard","I271";
;
CDS_LIB"mstr_standard"
BODY_TYPE"PLUMBING"
HDL_TAP"TRUE";
"B \NAC \NWC"8;
"S \NAC"
BN"3"52;
%"TAP"
"1","(-5875,4575)","2","mstr_standard","I272";
;
CDS_LIB"mstr_standard"
BODY_TYPE"PLUMBING"
HDL_TAP"TRUE";
"B \NAC \NWC"7;
"S \NAC"
BN"4"41;
%"TAP"
"1","(-5875,4375)","2","mstr_standard","I273";
;
CDS_LIB"mstr_standard"
BODY_TYPE"PLUMBING"
HDL_TAP"TRUE";
"B \NAC \NWC"7;
"S \NAC"
BN"6"58;
%"TAP"
"1","(-5875,4475)","2","mstr_standard","I274";
;
CDS_LIB"mstr_standard"
BODY_TYPE"PLUMBING"
HDL_TAP"TRUE";
"B \NAC \NWC"7;
"S \NAC"
BN"5"59;
%"TAP"
"1","(-5875,4275)","2","mstr_standard","I275";
;
CDS_LIB"mstr_standard"
BODY_TYPE"PLUMBING"
HDL_TAP"TRUE";
"B \NAC \NWC"7;
"S \NAC"
BN"7"57;
%"TAP"
"1","(-5875,4175)","2","mstr_standard","I276";
;
CDS_LIB"mstr_standard"
BODY_TYPE"PLUMBING"
HDL_TAP"TRUE";
"B \NAC \NWC"7;
"S \NAC"
BN"8"56;
%"TAP"
"1","(-6075,4425)","2","mstr_standard","I277";
;
CDS_LIB"mstr_standard"
BODY_TYPE"PLUMBING"
HDL_TAP"TRUE";
"B \NAC \NWC"8;
"S \NAC"
BN"5"48;
%"TAP"
"1","(-6075,4525)","2","mstr_standard","I278";
;
CDS_LIB"mstr_standard"
BODY_TYPE"PLUMBING"
HDL_TAP"TRUE";
"B \NAC \NWC"8;
"S \NAC"
BN"4"50;
%"TAP"
"1","(-6075,4325)","2","mstr_standard","I279";
;
CDS_LIB"mstr_standard"
BODY_TYPE"PLUMBING"
HDL_TAP"TRUE";
"B \NAC \NWC"8;
"S \NAC"
BN"6"46;
%"TAP"
"1","(-6075,4225)","2","mstr_standard","I280";
;
CDS_LIB"mstr_standard"
BODY_TYPE"PLUMBING"
HDL_TAP"TRUE";
"B \NAC \NWC"8;
"S \NAC"
BN"7"44;
%"TAP"
"1","(-6075,4125)","2","mstr_standard","I281";
;
CDS_LIB"mstr_standard"
BODY_TYPE"PLUMBING"
HDL_TAP"TRUE";
"B \NAC \NWC"8;
"S \NAC"
BN"8"42;
%"TAP"
"1","(-5875,4075)","2","mstr_standard","I286";
;
CDS_LIB"mstr_standard"
BODY_TYPE"PLUMBING"
HDL_TAP"TRUE";
"B \NAC \NWC"7;
"S \NAC"
BN"9"25;
%"TAP"
"1","(-6075,3875)","2","mstr_standard","I287";
;
CDS_LIB"mstr_standard"
BODY_TYPE"PLUMBING"
HDL_TAP"TRUE";
"B \NAC \NWC"9;
"S \NAC"
BN"0"39;
%"TAP"
"1","(-6075,4025)","2","mstr_standard","I288";
;
CDS_LIB"mstr_standard"
BODY_TYPE"PLUMBING"
HDL_TAP"TRUE";
"B \NAC \NWC"8;
"S \NAC"
BN"9"40;
%"TAP"
"1","(-6075,3825)","2","mstr_standard","I289";
;
CDS_LIB"mstr_standard"
BODY_TYPE"PLUMBING"
HDL_TAP"TRUE";
"B \NAC \NWC"9;
"S \NAC"
BN"1"37;
%"TAP"
"1","(-6075,3725)","2","mstr_standard","I290";
;
CDS_LIB"mstr_standard"
BODY_TYPE"PLUMBING"
HDL_TAP"TRUE";
"B \NAC \NWC"9;
"S \NAC"
BN"3"33;
%"TAP"
"1","(-6075,3775)","2","mstr_standard","I291";
;
CDS_LIB"mstr_standard"
BODY_TYPE"PLUMBING"
HDL_TAP"TRUE";
"B \NAC \NWC"9;
"S \NAC"
BN"2"35;
%"TAP"
"1","(-6075,3675)","2","mstr_standard","I292";
;
CDS_LIB"mstr_standard"
BODY_TYPE"PLUMBING"
HDL_TAP"TRUE";
"B \NAC \NWC"9;
"S \NAC"
BN"4"31;
%"TAP"
"1","(-6075,3625)","2","mstr_standard","I293";
;
CDS_LIB"mstr_standard"
BODY_TYPE"PLUMBING"
HDL_TAP"TRUE";
"B \NAC \NWC"9;
"S \NAC"
BN"5"29;
%"TAP"
"1","(-6075,3575)","2","mstr_standard","I294";
;
CDS_LIB"mstr_standard"
BODY_TYPE"PLUMBING"
HDL_TAP"TRUE";
"B \NAC \NWC"9;
"S \NAC"
BN"6"27;
%"TAP"
"1","(-6075,3425)","2","mstr_standard","I295";
;
CDS_LIB"mstr_standard"
BODY_TYPE"PLUMBING"
HDL_TAP"TRUE";
"B \NAC \NWC"10;
"S \NAC"
BN"1"36;
%"TAP"
"1","(-6075,3475)","2","mstr_standard","I296";
;
CDS_LIB"mstr_standard"
BODY_TYPE"PLUMBING"
HDL_TAP"TRUE";
"B \NAC \NWC"10;
"S \NAC"
BN"0"38;
%"TAP"
"1","(-6075,3375)","2","mstr_standard","I297";
;
CDS_LIB"mstr_standard"
BODY_TYPE"PLUMBING"
HDL_TAP"TRUE";
"B \NAC \NWC"10;
"S \NAC"
BN"2"34;
%"TAP"
"1","(-6075,3325)","2","mstr_standard","I298";
;
CDS_LIB"mstr_standard"
BODY_TYPE"PLUMBING"
HDL_TAP"TRUE";
"B \NAC \NWC"10;
"S \NAC"
BN"3"32;
%"TAP"
"1","(-6075,3175)","2","mstr_standard","I299";
;
CDS_LIB"mstr_standard"
BODY_TYPE"PLUMBING"
HDL_TAP"TRUE";
"B \NAC \NWC"10;
"S \NAC"
BN"6"26;
%"TAP"
"1","(-6075,3275)","2","mstr_standard","I300";
;
CDS_LIB"mstr_standard"
BODY_TYPE"PLUMBING"
HDL_TAP"TRUE";
"B \NAC \NWC"10;
"S \NAC"
BN"4"30;
%"TAP"
"1","(-6075,3225)","2","mstr_standard","I301";
;
CDS_LIB"mstr_standard"
BODY_TYPE"PLUMBING"
HDL_TAP"TRUE";
"B \NAC \NWC"10;
"S \NAC"
BN"5"28;
%"Q_RES"
"1","(-6750,2175)","0","pure_quanta","I314";
;
LOCATION"R501"
$SEC"1"
CDS_SEC"1"
PACK_TYPE"0402LF"
TOLERANCE"1%"
VALUE"15"
MATERIAL"CHIP"
WATTAGE"1/16W"
CDS_LIB"pure_quanta"
PART_NUMBER"CS01502FB03";
"B"
$PN"2"12;
"A"
$PN"1"11;
END.
